FILE_TYPE = CONNECTIVITY;
{Allegro Design Entry HDL 16.6-p007 (v16-6-112F) 10/10/2012}
"PAGE_NUMBER" = 171;
0"NC";
END.
